# BASEBOARD_FAB2 (Tioga Pass) — schematic netlist excerpt (pin names and nets, part order shuffled) for the footprints in the layout excerpt that follows; sources: Cadence DE-HDL packaged netlist, KiCad conversion of Wiwynn_Tioga_Pass_MB.brd

C9N18  CAP  0.22UF 16V 10% X7R  pkg 0402  page 182 : A = P3E_CPU1_PE3_MP_C_TXN<8> ; B = P3E_CPU1_PE3_MP_TXN<8>
R7D36  RES  0.0 5% CHIP  pkg 0402  page 104 : A = FM_156M_CPU1_BRD_OSC_EN ; B = FM_CPU1_STL_BRD_OSC_EN
R1W38  RES  0.0 5% CHIP  pkg 0402  page 176 : A = SMB_DEBUG_STBY_LVC3_SCL_CONN ; B = SMB_DEBUG_STBY_LVC3_SCL_R1

(kicad_pcb
	(version 20260206)
	(generator "pcbnew")
	(generator_version "10.0")
	(general
		(thickness 1.6)
		(legacy_teardrops no)
	)
	(paper "A4")
	(title_block
		(title "Wiwynn_Tioga_Pass_MB.brd")
		(comment 1 "Tioga Pass / footprints 4022-4024 of 4770")
	)
	(layers
		(0 "F.Cu" signal "TOP")
		(4 "In1.Cu" signal "L2GND")
		(6 "In2.Cu" signal "L3")
		(8 "In3.Cu" signal "L4GND")
		(10 "In4.Cu" signal "L5")
		(12 "In5.Cu" signal "L6GND")
		(14 "In6.Cu" signal "L7VCC")
		(16 "In7.Cu" signal "L8VCC")
		(18 "In8.Cu" signal "L9GND")
		(20 "In9.Cu" signal "L10")
		(22 "In10.Cu" signal "L11GND")
		(24 "In11.Cu" signal "L12")
		(26 "In12.Cu" signal "L13GND")
		(2 "B.Cu" signal "BOTTOM")
		(9 "F.Adhes" user "F.Adhesive")
		(11 "B.Adhes" user "B.Adhesive")
		(13 "F.Paste" user "Package Geometry/Pastemask Top")
		(15 "B.Paste" user "Package Geometry/Pastemask Bottom")
		(5 "F.SilkS" user "Ref Des/Silkscreen Top")
		(7 "B.SilkS" user "Ref Des/Silkscreen Bottom")
		(1 "F.Mask" user "Board Geometry/Soldermask Top")
		(3 "B.Mask" user "Board Geometry/Soldermask Bottom")
		(17 "Dwgs.User" user "User.Drawings")
		(19 "Cmts.User" user "User.Comments")
		(21 "Eco1.User" user "User.Eco1")
		(23 "Eco2.User" user "User.Eco2")
		(25 "Edge.Cuts" user "Board Geometry/Outline")
		(27 "Margin" user)
		(31 "F.CrtYd" user "Package Geometry/Place Bound Top")
		(29 "B.CrtYd" user "Package Geometry/Place Bound Bottom")
		(35 "F.Fab" user "Ref Des/Assembly Top")
		(33 "B.Fab" user "Ref Des/Assembly Bottom")
	)
	(footprint ""
		(layer "B.Cu")
		(at 477.081088 -132.83311)
		(property "Reference" "R1W38"
			(at 0.8382 -0.67818 0)
			(unlocked yes)
			(layer "B.SilkS")
			(effects
				(font
					(size 0.4064 0.254)
					(thickness 0.1524)
				)
				(justify left mirror)
			)
		)
		(property "Value" ""
			(at 0 0 0)
			(layer "B.Fab")
			(effects
				(font
					(size 1.27 1.27)
				)
				(justify mirror)
			)
		)
		(duplicate_pad_numbers_are_jumpers no)
		(fp_poly
			(pts
				(xy 0.2794 -0.1016) (xy -0.2794 -0.1016) (xy -0.2794 0.9906) (xy 0.2794 0.9906)
			)
			(stroke
				(width 0)
				(type default)
			)
			(fill no)
			(layer "B.CrtYd")
		)
		(fp_line
			(start -0.2794 -0.1016)
			(end 0.2794 -0.1016)
			(stroke
				(width 0.1)
				(type default)
			)
			(layer "B.Fab")
		)
		(fp_line
			(start -0.2794 0.9906)
			(end -0.2794 -0.1016)
			(stroke
				(width 0.1)
				(type default)
			)
			(layer "B.Fab")
		)
		(fp_line
			(start 0.2794 -0.1016)
			(end 0.2794 0.9906)
			(stroke
				(width 0.1)
				(type default)
			)
			(layer "B.Fab")
		)
		(fp_line
			(start 0.2794 0.9906)
			(end -0.2794 0.9906)
			(stroke
				(width 0.1)
				(type default)
			)
			(layer "B.Fab")
		)
		(pad "1" smd rect
			(at 0 0 180)
			(size 0.508 0.508)
			(layers "B.Cu" "B.Mask" "B.Paste")
			(net "SMB_DEBUG_STBY_LVC3_SCL_CONN")
		)
		(pad "2" smd rect
			(at 0 0.889 180)
			(size 0.508 0.508)
			(layers "B.Cu" "B.Mask" "B.Paste")
			(net "SMB_DEBUG_STBY_LVC3_SCL_R1")
		)
		(zone
			(layer "B.Cu")
			(hatch none 0.5)
			(connect_pads
				(clearance 0)
			)
			(min_thickness 0.25)
			(keepout
				(tracks allowed)
				(vias not_allowed)
				(pads allowed)
				(copperpour not_allowed)
				(footprints allowed)
			)
			(placement
				(enabled no)
				(sheetname "")
			)
			(fill
				(thermal_gap 0.5)
				(thermal_bridge_width 0.5)
				(island_removal_mode 0)
			)
			(polygon
				(pts
					(xy 477.335088 -132.57911) (xy 476.827088 -132.57911) (xy 476.827088 -132.19811) (xy 477.335088 -132.19811)
				)
			)
		)
		(zone
			(layer "B.Cu")
			(hatch none 0.5)
			(connect_pads
				(clearance 0)
			)
			(min_thickness 0.25)
			(keepout
				(tracks not_allowed)
				(vias allowed)
				(pads allowed)
				(copperpour not_allowed)
				(footprints allowed)
			)
			(placement
				(enabled no)
				(sheetname "")
			)
			(fill
				(thermal_gap 0.5)
				(thermal_bridge_width 0.5)
				(island_removal_mode 0)
			)
			(polygon
				(pts
					(xy 477.335088 -132.19811) (xy 476.827088 -132.19811) (xy 476.827088 -132.57911) (xy 477.335088 -132.57911)
				)
			)
		)
	)
	(footprint ""
		(layer "B.Cu")
		(at 365.506 -77.5716 -90)
		(property "Reference" "R7D36"
			(at 0 0 90)
			(layer "B.SilkS")
			(hide yes)
			(effects
				(font
					(size 1.27 1.27)
				)
				(justify mirror)
			)
		)
		(property "Value" ""
			(at 0 0 90)
			(layer "B.Fab")
			(effects
				(font
					(size 1.27 1.27)
				)
				(justify mirror)
			)
		)
		(duplicate_pad_numbers_are_jumpers no)
		(fp_poly
			(pts
				(xy 0.2794 -0.1016) (xy -0.2794 -0.1016) (xy -0.2794 0.9906) (xy 0.2794 0.9906)
			)
			(stroke
				(width 0)
				(type default)
			)
			(fill no)
			(layer "B.CrtYd")
		)
		(fp_line
			(start -0.2794 0.9906)
			(end -0.2794 -0.1016)
			(stroke
				(width 0.1)
				(type default)
			)
			(layer "B.Fab")
		)
		(fp_line
			(start 0.2794 0.9906)
			(end -0.2794 0.9906)
			(stroke
				(width 0.1)
				(type default)
			)
			(layer "B.Fab")
		)
		(fp_line
			(start -0.2794 -0.1016)
			(end 0.2794 -0.1016)
			(stroke
				(width 0.1)
				(type default)
			)
			(layer "B.Fab")
		)
		(fp_line
			(start 0.2794 -0.1016)
			(end 0.2794 0.9906)
			(stroke
				(width 0.1)
				(type default)
			)
			(layer "B.Fab")
		)
		(pad "1" smd rect
			(at 0 0 90)
			(size 0.508 0.508)
			(layers "B.Cu" "B.Mask" "B.Paste")
			(net "FM_156M_CPU1_BRD_OSC_EN")
		)
		(pad "2" smd rect
			(at 0 0.889 90)
			(size 0.508 0.508)
			(layers "B.Cu" "B.Mask" "B.Paste")
			(net "FM_CPU1_STL_BRD_OSC_EN")
		)
		(zone
			(layer "B.Cu")
			(hatch none 0.5)
			(connect_pads
				(clearance 0)
			)
			(min_thickness 0.25)
			(keepout
				(tracks not_allowed)
				(vias allowed)
				(pads allowed)
				(copperpour not_allowed)
				(footprints allowed)
			)
			(placement
				(enabled no)
				(sheetname "")
			)
			(fill
				(thermal_gap 0.5)
				(thermal_bridge_width 0.5)
				(island_removal_mode 0)
			)
			(polygon
				(pts
					(xy 364.871 -77.3176) (xy 364.871 -77.8256) (xy 365.252 -77.8256) (xy 365.252 -77.3176)
				)
			)
		)
		(zone
			(layer "B.Cu")
			(hatch none 0.5)
			(connect_pads
				(clearance 0)
			)
			(min_thickness 0.25)
			(keepout
				(tracks allowed)
				(vias not_allowed)
				(pads allowed)
				(copperpour not_allowed)
				(footprints allowed)
			)
			(placement
				(enabled no)
				(sheetname "")
			)
			(fill
				(thermal_gap 0.5)
				(thermal_bridge_width 0.5)
				(island_removal_mode 0)
			)
			(polygon
				(pts
					(xy 365.252 -77.3176) (xy 365.252 -77.8256) (xy 364.871 -77.8256) (xy 364.871 -77.3176)
				)
			)
		)
	)
	(footprint ""
		(layer "B.Cu")
		(at 13.10894 -97.11436 90)
		(property "Reference" "C9N18"
			(at 0 0 90)
			(layer "B.SilkS")
			(hide yes)
			(effects
				(font
					(size 1.27 1.27)
				)
				(justify mirror)
			)
		)
		(property "Value" ""
			(at 0 0 90)
			(layer "B.Fab")
			(effects
				(font
					(size 1.27 1.27)
				)
				(justify mirror)
			)
		)
		(duplicate_pad_numbers_are_jumpers no)
		(fp_poly
			(pts
				(xy -0.3048 -0.1016) (xy -0.3048 0.9906) (xy 0.3048 0.9906) (xy 0.3048 -0.1016)
			)
			(stroke
				(width 0)
				(type default)
			)
			(fill no)
			(layer "B.CrtYd")
		)
		(fp_line
			(start 0.3048 -0.1016)
			(end 0.3048 0.9906)
			(stroke
				(width 0.1)
				(type default)
			)
			(layer "B.Fab")
		)
		(fp_line
			(start -0.3048 -0.1016)
			(end 0.3048 -0.1016)
			(stroke
				(width 0.1)
				(type default)
			)
			(layer "B.Fab")
		)
		(fp_line
			(start 0.3048 0.9906)
			(end -0.3048 0.9906)
			(stroke
				(width 0.1)
				(type default)
			)
			(layer "B.Fab")
		)
		(fp_line
			(start -0.3048 0.9906)
			(end -0.3048 -0.1016)
			(stroke
				(width 0.1)
				(type default)
			)
			(layer "B.Fab")
		)
		(pad "1" smd rect
			(at 0 0 270)
			(size 0.508 0.508)
			(layers "B.Cu" "B.Mask" "B.Paste")
			(net "P3E_CPU1_PE3_MP_C_TXN<8>")
		)
		(pad "2" smd rect
			(at 0 0.889 270)
			(size 0.508 0.508)
			(layers "B.Cu" "B.Mask" "B.Paste")
			(net "P3E_CPU1_PE3_MP_TXN<8>")
		)
		(zone
			(layer "B.Cu")
			(hatch none 0.5)
			(connect_pads
				(clearance 0)
			)
			(min_thickness 0.25)
			(keepout
				(tracks allowed)
				(vias not_allowed)
				(pads allowed)
				(copperpour not_allowed)
				(footprints allowed)
			)
			(placement
				(enabled no)
				(sheetname "")
			)
			(fill
				(thermal_gap 0.5)
				(thermal_bridge_width 0.5)
				(island_removal_mode 0)
			)
			(polygon
				(pts
					(xy 13.36294 -97.36836) (xy 13.36294 -96.86036) (xy 13.74394 -96.86036) (xy 13.74394 -97.36836)
				)
			)
		)
		(zone
			(layer "B.Cu")
			(hatch none 0.5)
			(connect_pads
				(clearance 0)
			)
			(min_thickness 0.25)
			(keepout
				(tracks not_allowed)
				(vias allowed)
				(pads allowed)
				(copperpour not_allowed)
				(footprints allowed)
			)
			(placement
				(enabled no)
				(sheetname "")
			)
			(fill
				(thermal_gap 0.5)
				(thermal_bridge_width 0.5)
				(island_removal_mode 0)
			)
			(polygon
				(pts
					(xy 13.74394 -97.36836) (xy 13.74394 -96.86036) (xy 13.36294 -96.86036) (xy 13.36294 -97.36836)
				)
			)
		)
	)
)
